(kicad_pcb
	(version 20260206)
	(generator "pcbnew")
	(generator_version "10.0")
	(general
		(thickness 1.6)
		(legacy_teardrops no)
	)
	(paper "A4")
	(title_block
		(title "timecard-production-celestica-r4006 — R4006-B0001-02_R01.brd")
		(comment 1 "Time Appliance Project (Time Card) / footprints 961-965 of 1113")
	)
	(layers
		(0 "F.Cu" signal "TOP")
		(4 "In1.Cu" signal "L02_GND1")
		(6 "In2.Cu" signal "L03_SIG1")
		(8 "In3.Cu" signal "L04_GND2")
		(10 "In4.Cu" signal "L05_VCC1")
		(12 "In5.Cu" signal "L06_VCC2")
		(14 "In6.Cu" signal "L07_GND3")
		(16 "In7.Cu" signal "L08_SIG2")
		(18 "In8.Cu" signal "L09_GND4")
		(2 "B.Cu" signal "BOTTOM")
		(9 "F.Adhes" user "F.Adhesive")
		(11 "B.Adhes" user "B.Adhesive")
		(13 "F.Paste" user "Package Geometry/Pastemask Top")
		(15 "B.Paste" user "Package Geometry/Pastemask Bottom")
		(5 "F.SilkS" user "Ref Des/Silkscreen Top")
		(7 "B.SilkS" user "Ref Des/Silkscreen Bottom")
		(1 "F.Mask" user "Board Geometry/Soldermask Top")
		(3 "B.Mask" user "Board Geometry/Soldermask Bottom")
		(17 "Dwgs.User" user "User.Drawings")
		(19 "Cmts.User" user "User.Comments")
		(21 "Eco1.User" user "User.Eco1")
		(23 "Eco2.User" user "User.Eco2")
		(25 "Edge.Cuts" user "Board Geometry/Outline")
		(27 "Margin" user)
		(31 "F.CrtYd" user "Package Geometry/Place Bound Top")
		(29 "B.CrtYd" user "Package Geometry/Place Bound Bottom")
		(35 "F.Fab" user "Ref Des/Assembly Top")
		(33 "B.Fab" user "Ref Des/Assembly Bottom")
	)
	(footprint ""
		(layer "B.Cu")
		(at 55.1942 -74.9808 90)
		(property "Reference" "R416"
			(at 4.064 0.08763 270)
			(unlocked yes)
			(layer "B.SilkS")
			(effects
				(font
					(size 0.7874 0.5842)
					(thickness 0.1524)
				)
				(justify mirror)
			)
		)
		(property "Value" "VAL*"
			(at -0.02032 2.13233 90)
			(unlocked yes)
			(layer "B.Fab")
			(hide yes)
			(effects
				(font
					(size 0.7874 0.5842)
					(thickness 0.1524)
				)
				(justify mirror)
			)
		)
		(property "Device Type" "RESISTOR-G155-11001-01,1KOHM,1%"
			(at -0.008382 1.210564 90)
			(unlocked yes)
			(layer "B.Fab")
			(hide yes)
			(effects
				(font
					(size 0.7874 0.5842)
					(thickness 0.1524)
				)
				(justify mirror)
			)
		)
		(property "User Part Number" "PARTNUM*"
			(at -0.02032 4.024884 90)
			(unlocked yes)
			(layer "Cmts.User")
			(hide yes)
			(effects
				(font
					(size 0.7874 0.5842)
					(thickness 0.1524)
				)
				(justify mirror)
			)
		)
		(property "Tolerance" "TOL*"
			(at -0.044704 3.05435 90)
			(unlocked yes)
			(layer "Cmts.User")
			(hide yes)
			(effects
				(font
					(size 0.7874 0.5842)
					(thickness 0.1524)
				)
				(justify mirror)
			)
		)
		(duplicate_pad_numbers_are_jumpers no)
		(fp_line
			(start 1.143 -0.5588)
			(end 1.143 0.5588)
			(stroke
				(width 0.1)
				(type default)
			)
			(layer "B.SilkS")
		)
		(fp_line
			(start -1.143 -0.5588)
			(end 1.143 -0.5588)
			(stroke
				(width 0.1)
				(type default)
			)
			(layer "B.SilkS")
		)
		(fp_line
			(start 1.143 0.5588)
			(end -1.143 0.5588)
			(stroke
				(width 0.1)
				(type default)
			)
			(layer "B.SilkS")
		)
		(fp_line
			(start -1.143 0.5588)
			(end -1.143 -0.5588)
			(stroke
				(width 0.1)
				(type default)
			)
			(layer "B.SilkS")
		)
		(fp_rect
			(start 1.143 0.5588)
			(end -1.143 -0.5588)
			(stroke
				(width 0)
				(type default)
			)
			(fill no)
			(layer "B.CrtYd")
		)
		(fp_line
			(start 0.508 -0.3048)
			(end 0.508 0.3048)
			(stroke
				(width 0.1)
				(type default)
			)
			(layer "B.Fab")
		)
		(fp_line
			(start -0.508 -0.3048)
			(end 0.508 -0.3048)
			(stroke
				(width 0.1)
				(type default)
			)
			(layer "B.Fab")
		)
		(fp_line
			(start 0.508 0.3048)
			(end -0.508 0.3048)
			(stroke
				(width 0.1)
				(type default)
			)
			(layer "B.Fab")
		)
		(fp_line
			(start -0.508 0.3048)
			(end -0.508 -0.3048)
			(stroke
				(width 0.1)
				(type default)
			)
			(layer "B.Fab")
		)
		(pad "1" smd rect
			(at 0.5334 0 270)
			(size 0.7112 0.6096)
			(layers "B.Cu" "B.Mask" "B.Paste")
			(net "UNNAMED_6_LM75BDPTSSOP8_I59_A0")
		)
		(pad "2" smd rect
			(at -0.5334 0 270)
			(size 0.7112 0.6096)
			(layers "B.Cu" "B.Mask" "B.Paste")
			(net "SG")
		)
		(zone
			(layer "B.Cu")
			(hatch none 0.5)
			(connect_pads
				(clearance 0)
			)
			(min_thickness 0.25)
			(keepout
				(tracks allowed)
				(vias not_allowed)
				(pads allowed)
				(copperpour not_allowed)
				(footprints allowed)
			)
			(placement
				(enabled no)
				(sheetname "")
			)
			(fill
				(thermal_gap 0.5)
				(thermal_bridge_width 0.5)
				(island_removal_mode 0)
			)
			(polygon
				(pts
					(xy 55.499 -75.057) (xy 54.8894 -75.057) (xy 54.8894 -74.9046) (xy 55.499 -74.9046)
				)
			)
		)
		(zone
			(layer "B.Cu")
			(hatch none 0.5)
			(connect_pads
				(clearance 0)
			)
			(min_thickness 0.25)
			(keepout
				(tracks not_allowed)
				(vias allowed)
				(pads allowed)
				(copperpour not_allowed)
				(footprints allowed)
			)
			(placement
				(enabled no)
				(sheetname "")
			)
			(fill
				(thermal_gap 0.5)
				(thermal_bridge_width 0.5)
				(island_removal_mode 0)
			)
			(polygon
				(pts
					(xy 55.499 -75.057) (xy 54.8894 -75.057) (xy 54.8894 -74.9046) (xy 55.499 -74.9046)
				)
			)
		)
	)
	(footprint ""
		(layer "B.Cu")
		(at 85.09 -56.134 180)
		(property "Reference" "R77"
			(at 2.032 -1.18237 0)
			(unlocked yes)
			(layer "B.SilkS")
			(effects
				(font
					(size 0.7874 0.5842)
					(thickness 0.1524)
				)
				(justify mirror)
			)
		)
		(property "Value" "VAL*"
			(at -0.02032 2.13233 180)
			(unlocked yes)
			(layer "B.Fab")
			(hide yes)
			(effects
				(font
					(size 0.7874 0.5842)
					(thickness 0.1524)
				)
				(justify mirror)
			)
		)
		(property "Device Type" "RESISTOR-G155-133R0-01,33OHM,1%"
			(at -0.008382 1.210564 180)
			(unlocked yes)
			(layer "B.Fab")
			(hide yes)
			(effects
				(font
					(size 0.7874 0.5842)
					(thickness 0.1524)
				)
				(justify mirror)
			)
		)
		(property "User Part Number" "PARTNUM*"
			(at -0.02032 4.024884 180)
			(unlocked yes)
			(layer "Cmts.User")
			(hide yes)
			(effects
				(font
					(size 0.7874 0.5842)
					(thickness 0.1524)
				)
				(justify mirror)
			)
		)
		(property "Tolerance" "TOL*"
			(at -0.044704 3.05435 180)
			(unlocked yes)
			(layer "Cmts.User")
			(hide yes)
			(effects
				(font
					(size 0.7874 0.5842)
					(thickness 0.1524)
				)
				(justify mirror)
			)
		)
		(duplicate_pad_numbers_are_jumpers no)
		(fp_line
			(start 1.143 0.5588)
			(end -1.143 0.5588)
			(stroke
				(width 0.1)
				(type default)
			)
			(layer "B.SilkS")
		)
		(fp_line
			(start 1.143 -0.5588)
			(end 1.143 0.5588)
			(stroke
				(width 0.1)
				(type default)
			)
			(layer "B.SilkS")
		)
		(fp_line
			(start -1.143 0.5588)
			(end -1.143 -0.5588)
			(stroke
				(width 0.1)
				(type default)
			)
			(layer "B.SilkS")
		)
		(fp_line
			(start -1.143 -0.5588)
			(end 1.143 -0.5588)
			(stroke
				(width 0.1)
				(type default)
			)
			(layer "B.SilkS")
		)
		(fp_rect
			(start 1.143 -0.5588)
			(end -1.143 0.5588)
			(stroke
				(width 0)
				(type default)
			)
			(fill no)
			(layer "B.CrtYd")
		)
		(fp_line
			(start 0.508 0.3048)
			(end -0.508 0.3048)
			(stroke
				(width 0.1)
				(type default)
			)
			(layer "B.Fab")
		)
		(fp_line
			(start 0.508 -0.3048)
			(end 0.508 0.3048)
			(stroke
				(width 0.1)
				(type default)
			)
			(layer "B.Fab")
		)
		(fp_line
			(start -0.508 0.3048)
			(end -0.508 -0.3048)
			(stroke
				(width 0.1)
				(type default)
			)
			(layer "B.Fab")
		)
		(fp_line
			(start -0.508 -0.3048)
			(end 0.508 -0.3048)
			(stroke
				(width 0.1)
				(type default)
			)
			(layer "B.Fab")
		)
		(pad "1" smd rect
			(at 0.5334 0)
			(size 0.7112 0.6096)
			(layers "B.Cu" "B.Mask" "B.Paste")
			(net "BNO080_I2C_SCL")
		)
		(pad "2" smd rect
			(at -0.5334 0)
			(size 0.7112 0.6096)
			(layers "B.Cu" "B.Mask" "B.Paste")
			(net "R_BNO080_I2C_SCL")
		)
		(zone
			(layer "B.Cu")
			(hatch none 0.5)
			(connect_pads
				(clearance 0)
			)
			(min_thickness 0.25)
			(keepout
				(tracks allowed)
				(vias not_allowed)
				(pads allowed)
				(copperpour not_allowed)
				(footprints allowed)
			)
			(placement
				(enabled no)
				(sheetname "")
			)
			(fill
				(thermal_gap 0.5)
				(thermal_bridge_width 0.5)
				(island_removal_mode 0)
			)
			(polygon
				(pts
					(xy 85.0138 -55.8292) (xy 85.1662 -55.8292) (xy 85.1662 -56.4388) (xy 85.0138 -56.4388)
				)
			)
		)
	)
	(footprint ""
		(layer "B.Cu")
		(at 36.7284 -97.8154 180)
		(property "Reference" "R47"
			(at 3.8354 -0.69977 0)
			(unlocked yes)
			(layer "B.SilkS")
			(effects
				(font
					(size 0.7874 0.5842)
					(thickness 0.1524)
				)
				(justify mirror)
			)
		)
		(property "Value" "VAL*"
			(at -0.02032 2.13233 180)
			(unlocked yes)
			(layer "B.Fab")
			(hide yes)
			(effects
				(font
					(size 0.7874 0.5842)
					(thickness 0.1524)
				)
				(justify mirror)
			)
		)
		(property "Tolerance" "TOL*"
			(at -0.044704 3.05435 180)
			(unlocked yes)
			(layer "Cmts.User")
			(hide yes)
			(effects
				(font
					(size 0.7874 0.5842)
					(thickness 0.1524)
				)
				(justify mirror)
			)
		)
		(property "User Part Number" "PARTNUM*"
			(at -0.02032 4.024884 180)
			(unlocked yes)
			(layer "Cmts.User")
			(hide yes)
			(effects
				(font
					(size 0.7874 0.5842)
					(thickness 0.1524)
				)
				(justify mirror)
			)
		)
		(property "Device Type" "RESISTOR-G155-11002-01,10KOHM,A"
			(at -0.008382 1.210564 180)
			(unlocked yes)
			(layer "B.Fab")
			(hide yes)
			(effects
				(font
					(size 0.7874 0.5842)
					(thickness 0.1524)
				)
				(justify mirror)
			)
		)
		(duplicate_pad_numbers_are_jumpers no)
		(fp_line
			(start 1.143 0.5588)
			(end -1.143 0.5588)
			(stroke
				(width 0.1)
				(type default)
			)
			(layer "B.SilkS")
		)
		(fp_line
			(start 1.143 -0.5588)
			(end 1.143 0.5588)
			(stroke
				(width 0.1)
				(type default)
			)
			(layer "B.SilkS")
		)
		(fp_line
			(start -1.143 0.5588)
			(end -1.143 -0.5588)
			(stroke
				(width 0.1)
				(type default)
			)
			(layer "B.SilkS")
		)
		(fp_line
			(start -1.143 -0.5588)
			(end 1.143 -0.5588)
			(stroke
				(width 0.1)
				(type default)
			)
			(layer "B.SilkS")
		)
		(fp_poly
			(pts
				(xy 1.143 0.5588) (xy -1.143 0.5588) (xy -1.143 -0.5588) (xy 1.143 -0.5588)
			)
			(stroke
				(width 0)
				(type default)
			)
			(fill no)
			(layer "B.CrtYd")
		)
		(fp_line
			(start 0.508 0.3048)
			(end -0.508 0.3048)
			(stroke
				(width 0.1)
				(type default)
			)
			(layer "B.Fab")
		)
		(fp_line
			(start 0.508 -0.3048)
			(end 0.508 0.3048)
			(stroke
				(width 0.1)
				(type default)
			)
			(layer "B.Fab")
		)
		(fp_line
			(start -0.508 0.3048)
			(end -0.508 -0.3048)
			(stroke
				(width 0.1)
				(type default)
			)
			(layer "B.Fab")
		)
		(fp_line
			(start -0.508 -0.3048)
			(end 0.508 -0.3048)
			(stroke
				(width 0.1)
				(type default)
			)
			(layer "B.Fab")
		)
		(pad "1" smd rect
			(at 0.5334 0)
			(size 0.7112 0.6096)
			(layers "B.Cu" "B.Mask" "B.Paste")
			(net "XP3R3V")
		)
		(pad "2" smd rect
			(at -0.5334 0)
			(size 0.7112 0.6096)
			(layers "B.Cu" "B.Mask" "B.Paste")
			(net "XP5R0V_PG")
		)
		(zone
			(layer "B.Cu")
			(hatch none 0.5)
			(connect_pads
				(clearance 0)
			)
			(min_thickness 0.25)
			(keepout
				(tracks allowed)
				(vias not_allowed)
				(pads allowed)
				(copperpour not_allowed)
				(footprints allowed)
			)
			(placement
				(enabled no)
				(sheetname "")
			)
			(fill
				(thermal_gap 0.5)
				(thermal_bridge_width 0.5)
				(island_removal_mode 0)
			)
			(polygon
				(pts
					(xy 36.6522 -98.1202) (xy 36.6522 -97.5106) (xy 36.8046 -97.5106) (xy 36.8046 -98.1202)
				)
			)
		)
		(zone
			(layer "B.Cu")
			(hatch none 0.5)
			(connect_pads
				(clearance 0)
			)
			(min_thickness 0.25)
			(keepout
				(tracks not_allowed)
				(vias allowed)
				(pads allowed)
				(copperpour not_allowed)
				(footprints allowed)
			)
			(placement
				(enabled no)
				(sheetname "")
			)
			(fill
				(thermal_gap 0.5)
				(thermal_bridge_width 0.5)
				(island_removal_mode 0)
			)
			(polygon
				(pts
					(xy 36.6522 -98.1202) (xy 36.6522 -97.5106) (xy 36.8046 -97.5106) (xy 36.8046 -98.1202)
				)
			)
		)
	)
	(footprint ""
		(layer "B.Cu")
		(at 117.348 -61.976 90)
		(property "Reference" "R224"
			(at 3.429 0.08763 270)
			(unlocked yes)
			(layer "B.SilkS")
			(effects
				(font
					(size 0.7874 0.5842)
					(thickness 0.1524)
				)
				(justify mirror)
			)
		)
		(property "Value" "VAL*"
			(at -0.02032 2.13233 90)
			(unlocked yes)
			(layer "B.Fab")
			(hide yes)
			(effects
				(font
					(size 0.7874 0.5842)
					(thickness 0.1524)
				)
				(justify mirror)
			)
		)
		(property "Device Type" "RESISTOR-G155-11001-01,1KOHM,1%"
			(at -0.008382 1.210564 90)
			(unlocked yes)
			(layer "B.Fab")
			(hide yes)
			(effects
				(font
					(size 0.7874 0.5842)
					(thickness 0.1524)
				)
				(justify mirror)
			)
		)
		(property "User Part Number" "PARTNUM*"
			(at -0.02032 4.024884 90)
			(unlocked yes)
			(layer "Cmts.User")
			(hide yes)
			(effects
				(font
					(size 0.7874 0.5842)
					(thickness 0.1524)
				)
				(justify mirror)
			)
		)
		(property "Tolerance" "TOL*"
			(at -0.044704 3.05435 90)
			(unlocked yes)
			(layer "Cmts.User")
			(hide yes)
			(effects
				(font
					(size 0.7874 0.5842)
					(thickness 0.1524)
				)
				(justify mirror)
			)
		)
		(duplicate_pad_numbers_are_jumpers no)
		(fp_line
			(start 1.143 -0.5588)
			(end 1.143 0.5588)
			(stroke
				(width 0.1)
				(type default)
			)
			(layer "B.SilkS")
		)
		(fp_line
			(start -1.143 -0.5588)
			(end 1.143 -0.5588)
			(stroke
				(width 0.1)
				(type default)
			)
			(layer "B.SilkS")
		)
		(fp_line
			(start 1.143 0.5588)
			(end -1.143 0.5588)
			(stroke
				(width 0.1)
				(type default)
			)
			(layer "B.SilkS")
		)
		(fp_line
			(start -1.143 0.5588)
			(end -1.143 -0.5588)
			(stroke
				(width 0.1)
				(type default)
			)
			(layer "B.SilkS")
		)
		(fp_rect
			(start -1.143 -0.5588)
			(end 1.143 0.5588)
			(stroke
				(width 0)
				(type default)
			)
			(fill no)
			(layer "B.CrtYd")
		)
		(fp_line
			(start 0.508 -0.3048)
			(end 0.508 0.3048)
			(stroke
				(width 0.1)
				(type default)
			)
			(layer "B.Fab")
		)
		(fp_line
			(start -0.508 -0.3048)
			(end 0.508 -0.3048)
			(stroke
				(width 0.1)
				(type default)
			)
			(layer "B.Fab")
		)
		(fp_line
			(start 0.508 0.3048)
			(end -0.508 0.3048)
			(stroke
				(width 0.1)
				(type default)
			)
			(layer "B.Fab")
		)
		(fp_line
			(start -0.508 0.3048)
			(end -0.508 -0.3048)
			(stroke
				(width 0.1)
				(type default)
			)
			(layer "B.Fab")
		)
		(pad "1" smd rect
			(at 0.5334 0 270)
			(size 0.7112 0.6096)
			(layers "B.Cu" "B.Mask" "B.Paste")
			(net "SG")
		)
		(pad "2" smd rect
			(at -0.5334 0 270)
			(size 0.7112 0.6096)
			(layers "B.Cu" "B.Mask" "B.Paste")
			(net "PUDC")
		)
		(zone
			(layer "B.Cu")
			(hatch none 0.5)
			(connect_pads
				(clearance 0)
			)
			(min_thickness 0.25)
			(keepout
				(tracks allowed)
				(vias not_allowed)
				(pads allowed)
				(copperpour not_allowed)
				(footprints allowed)
			)
			(placement
				(enabled no)
				(sheetname "")
			)
			(fill
				(thermal_gap 0.5)
				(thermal_bridge_width 0.5)
				(island_removal_mode 0)
			)
			(polygon
				(pts
					(xy 117.0432 -61.8998) (xy 117.6528 -61.8998) (xy 117.6528 -62.0522) (xy 117.0432 -62.0522)
				)
			)
		)
	)
	(footprint ""
		(layer "B.Cu")
		(at 13.462 -17.1704 -90)
		(property "Reference" "R123"
			(at -2.2606 -0.22225 270)
			(unlocked yes)
			(layer "B.SilkS")
			(effects
				(font
					(size 0.635 0.4064)
					(thickness 0.1524)
				)
				(justify mirror)
			)
		)
		(property "Value" "VAL*"
			(at -0.02032 2.13233 270)
			(unlocked yes)
			(layer "B.Fab")
			(hide yes)
			(effects
				(font
					(size 0.7874 0.5842)
					(thickness 0.1524)
				)
				(justify mirror)
			)
		)
		(property "Tolerance" "TOL*"
			(at -0.044704 3.05435 270)
			(unlocked yes)
			(layer "Cmts.User")
			(hide yes)
			(effects
				(font
					(size 0.7874 0.5842)
					(thickness 0.1524)
				)
				(justify mirror)
			)
		)
		(property "User Part Number" "PARTNUM*"
			(at -0.02032 4.024884 270)
			(unlocked yes)
			(layer "Cmts.User")
			(hide yes)
			(effects
				(font
					(size 0.7874 0.5842)
					(thickness 0.1524)
				)
				(justify mirror)
			)
		)
		(property "Device Type" "RESISTOR-G155-149R9-01,49.9OHMA"
			(at -0.008382 1.210564 270)
			(unlocked yes)
			(layer "B.Fab")
			(hide yes)
			(effects
				(font
					(size 0.7874 0.5842)
					(thickness 0.1524)
				)
				(justify mirror)
			)
		)
		(duplicate_pad_numbers_are_jumpers no)
		(fp_line
			(start -1.143 0.5588)
			(end -1.143 -0.5588)
			(stroke
				(width 0.1)
				(type default)
			)
			(layer "B.SilkS")
		)
		(fp_line
			(start 1.143 0.5588)
			(end -1.143 0.5588)
			(stroke
				(width 0.1)
				(type default)
			)
			(layer "B.SilkS")
		)
		(fp_line
			(start -1.143 -0.5588)
			(end 1.143 -0.5588)
			(stroke
				(width 0.1)
				(type default)
			)
			(layer "B.SilkS")
		)
		(fp_line
			(start 1.143 -0.5588)
			(end 1.143 0.5588)
			(stroke
				(width 0.1)
				(type default)
			)
			(layer "B.SilkS")
		)
		(fp_poly
			(pts
				(xy 1.143 0.5588) (xy -1.143 0.5588) (xy -1.143 -0.5588) (xy 1.143 -0.5588)
			)
			(stroke
				(width 0)
				(type default)
			)
			(fill no)
			(layer "B.CrtYd")
		)
		(fp_line
			(start -0.508 0.3048)
			(end -0.508 -0.3048)
			(stroke
				(width 0.1)
				(type default)
			)
			(layer "B.Fab")
		)
		(fp_line
			(start 0.508 0.3048)
			(end -0.508 0.3048)
			(stroke
				(width 0.1)
				(type default)
			)
			(layer "B.Fab")
		)
		(fp_line
			(start -0.508 -0.3048)
			(end 0.508 -0.3048)
			(stroke
				(width 0.1)
				(type default)
			)
			(layer "B.Fab")
		)
		(fp_line
			(start 0.508 -0.3048)
			(end 0.508 0.3048)
			(stroke
				(width 0.1)
				(type default)
			)
			(layer "B.Fab")
		)
		(pad "1" smd rect
			(at 0.5334 0 90)
			(size 0.7112 0.6096)
			(layers "B.Cu" "B.Mask" "B.Paste")
			(net "BF_SMA4_SIG_IO_CONN")
		)
		(pad "2" smd rect
			(at -0.5334 0 90)
			(size 0.7112 0.6096)
			(layers "B.Cu" "B.Mask" "B.Paste")
			(net "SMA4_SIG_IO_CONN")
		)
		(zone
			(layer "B.Cu")
			(hatch none 0.5)
			(connect_pads
				(clearance 0)
			)
			(min_thickness 0.25)
			(keepout
				(tracks allowed)
				(vias not_allowed)
				(pads allowed)
				(copperpour not_allowed)
				(footprints allowed)
			)
			(placement
				(enabled no)
				(sheetname "")
			)
			(fill
				(thermal_gap 0.5)
				(thermal_bridge_width 0.5)
				(island_removal_mode 0)
			)
			(polygon
				(pts
					(xy 13.1572 -17.0942) (xy 13.7668 -17.0942) (xy 13.7668 -17.2466) (xy 13.1572 -17.2466)
				)
			)
		)
		(zone
			(layer "B.Cu")
			(hatch none 0.5)
			(connect_pads
				(clearance 0)
			)
			(min_thickness 0.25)
			(keepout
				(tracks not_allowed)
				(vias allowed)
				(pads allowed)
				(copperpour not_allowed)
				(footprints allowed)
			)
			(placement
				(enabled no)
				(sheetname "")
			)
			(fill
				(thermal_gap 0.5)
				(thermal_bridge_width 0.5)
				(island_removal_mode 0)
			)
			(polygon
				(pts
					(xy 13.1572 -17.0942) (xy 13.7668 -17.0942) (xy 13.7668 -17.2466) (xy 13.1572 -17.2466)
				)
			)
		)
	)
)
